(kicad_pcb
	(version 20260206)
	(generator "pcbnew")
	(generator_version "10.0")
	(general
		(thickness 1.6)
		(legacy_teardrops no)
	)
	(paper "A4")
	(title_block
		(title "04192023_DAF0TMB3IC0_F0TG_MB_C_brd_V02_OCP.brd")
		(comment 1 "Grand Teton / footprints 605-608 of 8354")
	)
	(layers
		(0 "F.Cu" signal "TOP")
		(4 "In1.Cu" signal "GND")
		(6 "In2.Cu" signal "IN1")
		(8 "In3.Cu" signal "GND1")
		(10 "In4.Cu" signal "IN2")
		(12 "In5.Cu" signal "GND2")
		(14 "In6.Cu" signal "IN3")
		(16 "In7.Cu" signal "GND3")
		(18 "In8.Cu" signal "VCC")
		(20 "In9.Cu" signal "VCC1")
		(22 "In10.Cu" signal "GND4")
		(24 "In11.Cu" signal "IN4")
		(26 "In12.Cu" signal "GND5")
		(28 "In13.Cu" signal "IN5")
		(30 "In14.Cu" signal "GND6")
		(32 "In15.Cu" signal "IN6")
		(34 "In16.Cu" signal "GND7")
		(2 "B.Cu" signal "BOTTOM")
		(9 "F.Adhes" user "F.Adhesive")
		(11 "B.Adhes" user "B.Adhesive")
		(13 "F.Paste" user "Package Geometry/Pastemask Top")
		(15 "B.Paste" user "Package Geometry/Pastemask Bottom")
		(5 "F.SilkS" user "Ref Des/Silkscreen Top")
		(7 "B.SilkS" user "Ref Des/Silkscreen Bottom")
		(1 "F.Mask" user "Board Geometry/Soldermask Top")
		(3 "B.Mask" user "Board Geometry/Soldermask Bottom")
		(17 "Dwgs.User" user "User.Drawings")
		(19 "Cmts.User" user "User.Comments")
		(21 "Eco1.User" user "User.Eco1")
		(23 "Eco2.User" user "User.Eco2")
		(25 "Edge.Cuts" user "Board Geometry/Outline")
		(27 "Margin" user)
		(31 "F.CrtYd" user "Package Geometry/Place Bound Top")
		(29 "B.CrtYd" user "Package Geometry/Place Bound Bottom")
		(35 "F.Fab" user "Ref Des/Assembly Top")
		(33 "B.Fab" user "Ref Des/Assembly Bottom")
	)
	(footprint ""
		(layer "F.Cu")
		(at 401.501356 -178.905408 -90)
		(property "Reference" "PR502"
			(at 0 0 270)
			(layer "F.SilkS")
			(hide yes)
			(effects
				(font
					(size 1.27 1.27)
				)
			)
		)
		(property "Value" ""
			(at 0 0 270)
			(layer "F.Fab")
			(effects
				(font
					(size 1.27 1.27)
				)
			)
		)
		(duplicate_pad_numbers_are_jumpers no)
		(fp_line
			(start -0.7874 0.4064)
			(end -0.7874 -0.4064)
			(stroke
				(width 0.1524)
				(type default)
			)
			(layer "F.SilkS")
		)
		(fp_line
			(start 0.7874 0.4064)
			(end -0.7874 0.4064)
			(stroke
				(width 0.1524)
				(type default)
			)
			(layer "F.SilkS")
		)
		(fp_line
			(start -0.7874 -0.4064)
			(end 0.7874 -0.4064)
			(stroke
				(width 0.1524)
				(type default)
			)
			(layer "F.SilkS")
		)
		(fp_line
			(start 0.7874 -0.4064)
			(end 0.7874 0.4064)
			(stroke
				(width 0.1524)
				(type default)
			)
			(layer "F.SilkS")
		)
		(fp_line
			(start -0.67945 0.3048)
			(end -0.67945 -0.305054)
			(stroke
				(width 0.1)
				(type default)
			)
			(layer "F.Fab")
		)
		(fp_line
			(start -0.12065 0.3048)
			(end -0.67945 0.3048)
			(stroke
				(width 0.1)
				(type default)
			)
			(layer "F.Fab")
		)
		(fp_line
			(start 0.120396 0.3048)
			(end 0.120396 0.2794)
			(stroke
				(width 0.1)
				(type default)
			)
			(layer "F.Fab")
		)
		(fp_line
			(start 0.67945 0.3048)
			(end 0.120396 0.3048)
			(stroke
				(width 0.1)
				(type default)
			)
			(layer "F.Fab")
		)
		(fp_line
			(start -0.12065 0.2794)
			(end -0.12065 0.3048)
			(stroke
				(width 0.1)
				(type default)
			)
			(layer "F.Fab")
		)
		(fp_line
			(start 0.120396 0.2794)
			(end -0.12065 0.2794)
			(stroke
				(width 0.1)
				(type default)
			)
			(layer "F.Fab")
		)
		(fp_line
			(start -0.12065 -0.2794)
			(end 0.12065 -0.2794)
			(stroke
				(width 0.1)
				(type default)
			)
			(layer "F.Fab")
		)
		(fp_line
			(start 0.12065 -0.2794)
			(end 0.12065 -0.3048)
			(stroke
				(width 0.1)
				(type default)
			)
			(layer "F.Fab")
		)
		(fp_line
			(start 0.12065 -0.3048)
			(end 0.67945 -0.3048)
			(stroke
				(width 0.1)
				(type default)
			)
			(layer "F.Fab")
		)
		(fp_line
			(start 0.67945 -0.3048)
			(end 0.67945 0.3048)
			(stroke
				(width 0.1)
				(type default)
			)
			(layer "F.Fab")
		)
		(fp_line
			(start -0.67945 -0.305054)
			(end -0.12065 -0.305054)
			(stroke
				(width 0.1)
				(type default)
			)
			(layer "F.Fab")
		)
		(fp_line
			(start -0.12065 -0.305054)
			(end -0.12065 -0.2794)
			(stroke
				(width 0.1)
				(type default)
			)
			(layer "F.Fab")
		)
		(pad "1" smd circle
			(at -0.40005 0 270)
			(size 0 0)
			(layers "F.Cu" "F.Mask" "F.Paste")
			(net "SW_PVDDCR_SOC_P0_SW1_RC")
		)
		(pad "2" smd circle
			(at 0.40005 0 270)
			(size 0 0)
			(layers "F.Cu" "F.Mask" "F.Paste")
			(net "GND")
		)
	)
	(footprint ""
		(layer "F.Cu")
		(at 191.135 -133.568948 90)
		(property "Reference" "R588"
			(at 0 0 90)
			(layer "F.SilkS")
			(hide yes)
			(effects
				(font
					(size 1.27 1.27)
				)
			)
		)
		(property "Value" ""
			(at 0 0 90)
			(layer "F.Fab")
			(effects
				(font
					(size 1.27 1.27)
				)
			)
		)
		(duplicate_pad_numbers_are_jumpers no)
		(fp_line
			(start 0.7874 -0.4064)
			(end 0.7874 0.4064)
			(stroke
				(width 0.1524)
				(type default)
			)
			(layer "F.SilkS")
		)
		(fp_line
			(start -0.7874 -0.4064)
			(end 0.7874 -0.4064)
			(stroke
				(width 0.1524)
				(type default)
			)
			(layer "F.SilkS")
		)
		(fp_line
			(start 0.7874 0.4064)
			(end -0.7874 0.4064)
			(stroke
				(width 0.1524)
				(type default)
			)
			(layer "F.SilkS")
		)
		(fp_line
			(start -0.7874 0.4064)
			(end -0.7874 -0.4064)
			(stroke
				(width 0.1524)
				(type default)
			)
			(layer "F.SilkS")
		)
		(fp_line
			(start -0.12065 -0.305054)
			(end -0.12065 -0.2794)
			(stroke
				(width 0.1)
				(type default)
			)
			(layer "F.Fab")
		)
		(fp_line
			(start -0.67945 -0.305054)
			(end -0.12065 -0.305054)
			(stroke
				(width 0.1)
				(type default)
			)
			(layer "F.Fab")
		)
		(fp_line
			(start 0.67945 -0.3048)
			(end 0.67945 0.3048)
			(stroke
				(width 0.1)
				(type default)
			)
			(layer "F.Fab")
		)
		(fp_line
			(start 0.12065 -0.3048)
			(end 0.67945 -0.3048)
			(stroke
				(width 0.1)
				(type default)
			)
			(layer "F.Fab")
		)
		(fp_line
			(start 0.12065 -0.2794)
			(end 0.12065 -0.3048)
			(stroke
				(width 0.1)
				(type default)
			)
			(layer "F.Fab")
		)
		(fp_line
			(start -0.12065 -0.2794)
			(end 0.12065 -0.2794)
			(stroke
				(width 0.1)
				(type default)
			)
			(layer "F.Fab")
		)
		(fp_line
			(start 0.120396 0.2794)
			(end -0.12065 0.2794)
			(stroke
				(width 0.1)
				(type default)
			)
			(layer "F.Fab")
		)
		(fp_line
			(start -0.12065 0.2794)
			(end -0.12065 0.3048)
			(stroke
				(width 0.1)
				(type default)
			)
			(layer "F.Fab")
		)
		(fp_line
			(start 0.67945 0.3048)
			(end 0.120396 0.3048)
			(stroke
				(width 0.1)
				(type default)
			)
			(layer "F.Fab")
		)
		(fp_line
			(start 0.120396 0.3048)
			(end 0.120396 0.2794)
			(stroke
				(width 0.1)
				(type default)
			)
			(layer "F.Fab")
		)
		(fp_line
			(start -0.12065 0.3048)
			(end -0.67945 0.3048)
			(stroke
				(width 0.1)
				(type default)
			)
			(layer "F.Fab")
		)
		(fp_line
			(start -0.67945 0.3048)
			(end -0.67945 -0.305054)
			(stroke
				(width 0.1)
				(type default)
			)
			(layer "F.Fab")
		)
		(pad "1" smd circle
			(at -0.40005 0 90)
			(size 0 0)
			(layers "F.Cu" "F.Mask" "F.Paste")
			(net "SCM_USB_OC_R_N")
		)
		(pad "2" smd circle
			(at 0.40005 0 90)
			(size 0 0)
			(layers "F.Cu" "F.Mask" "F.Paste")
			(net "SCM_USB_OC_N")
		)
	)
	(footprint ""
		(layer "F.Cu")
		(at 191.246506 -351.320862)
		(property "Reference" "PU45"
			(at -3.032506 -7.935468 0)
			(unlocked yes)
			(layer "F.SilkS")
			(effects
				(font
					(size 0.7874 0.5842)
					(thickness 0.1524)
				)
				(justify left)
			)
		)
		(property "Value" ""
			(at 0 0 0)
			(layer "F.Fab")
			(effects
				(font
					(size 1.27 1.27)
				)
			)
		)
		(duplicate_pad_numbers_are_jumpers no)
		(fp_line
			(start -2.500122 -2.999994)
			(end -2.24409 -2.999994)
			(stroke
				(width 0.1524)
				(type default)
			)
			(layer "F.SilkS")
		)
		(fp_line
			(start -2.500122 -2.529078)
			(end -2.500122 -2.999994)
			(stroke
				(width 0.1524)
				(type default)
			)
			(layer "F.SilkS")
		)
		(fp_line
			(start -2.500122 0.6604)
			(end -2.500122 0.229108)
			(stroke
				(width 0.1524)
				(type default)
			)
			(layer "F.SilkS")
		)
		(fp_line
			(start -2.500122 2.999994)
			(end -2.500122 2.339594)
			(stroke
				(width 0.1524)
				(type default)
			)
			(layer "F.SilkS")
		)
		(fp_line
			(start -2.2987 2.999994)
			(end -2.500122 2.999994)
			(stroke
				(width 0.1524)
				(type default)
			)
			(layer "F.SilkS")
		)
		(fp_line
			(start 2.31394 -2.999994)
			(end 2.500122 -2.999994)
			(stroke
				(width 0.1524)
				(type default)
			)
			(layer "F.SilkS")
		)
		(fp_line
			(start 2.500122 -2.999994)
			(end 2.500122 -2.44348)
			(stroke
				(width 0.1524)
				(type default)
			)
			(layer "F.SilkS")
		)
		(fp_line
			(start 2.500122 2.339594)
			(end 2.500122 2.999994)
			(stroke
				(width 0.1524)
				(type default)
			)
			(layer "F.SilkS")
		)
		(fp_line
			(start 2.500122 2.999994)
			(end 2.2987 2.999994)
			(stroke
				(width 0.1524)
				(type default)
			)
			(layer "F.SilkS")
		)
		(fp_poly
			(pts
				(xy -2.768854 -2.421382) (xy -3.442462 -2.645918) (xy -2.99339 -3.09499)
			)
			(stroke
				(width 0)
				(type default)
			)
			(fill yes)
			(layer "F.SilkS")
		)
		(fp_line
			(start -2.500122 -2.999994)
			(end 2.500122 -2.999994)
			(stroke
				(width 0.1)
				(type default)
			)
			(layer "F.Fab")
		)
		(fp_line
			(start -2.500122 2.999994)
			(end -2.500122 -2.999994)
			(stroke
				(width 0.1)
				(type default)
			)
			(layer "F.Fab")
		)
		(fp_line
			(start 2.500122 -2.999994)
			(end 2.500122 2.999994)
			(stroke
				(width 0.1)
				(type default)
			)
			(layer "F.Fab")
		)
		(fp_line
			(start 2.500122 2.999994)
			(end -2.500122 2.999994)
			(stroke
				(width 0.1)
				(type default)
			)
			(layer "F.Fab")
		)
		(fp_poly
			(pts
				(xy -4.218432 -2.783078) (xy -4.218432 -1.767078) (xy -3.202432 -2.275078)
			)
			(stroke
				(width 0)
				(type default)
			)
			(fill yes)
			(layer "F.Fab")
		)
		(pad "1" smd rect
			(at -2.400046 -2.275078 90)
			(size 0.2286 0.6096)
			(layers "F.Cu" "F.Mask" "F.Paste")
			(net "PVDD11_S3_P1_VOS2")
		)
		(pad "2" smd rect
			(at -2.400046 -1.82499 90)
			(size 0.2286 0.6096)
			(layers "F.Cu" "F.Mask" "F.Paste")
			(net "GND")
		)
		(pad "3" smd rect
			(at -2.400046 -1.374902 90)
			(size 0.2286 0.6096)
			(layers "F.Cu" "F.Mask" "F.Paste")
			(net "PVDD11_S3_P1_VCC2")
		)
		(pad "4" smd rect
			(at -2.400046 -0.925068 90)
			(size 0.2286 0.6096)
			(layers "F.Cu" "F.Mask" "F.Paste")
			(net "PVDD11_S3_P1_PVCC")
		)
		(pad "5" smd rect
			(at -2.400046 -0.47498 90)
			(size 0.2286 0.6096)
			(layers "F.Cu" "F.Mask" "F.Paste")
			(net "GND")
		)
		(pad "6" smd rect
			(at -2.400046 -0.024892 90)
			(size 0.2286 0.6096)
			(layers "F.Cu" "F.Mask" "F.Paste")
			(net "NC_PVDD11_S3_P1_GL1_2")
		)
		(pad "7_9-20_24" smd circle
			(at 0 1.150112 90)
			(size 0 0)
			(layers "F.Cu" "F.Mask" "F.Paste")
			(net "GND")
		)
		(pad "10_19" smd rect
			(at 0 2.899918 90)
			(size 0.6096 4.318)
			(layers "F.Cu" "F.Mask" "F.Paste")
			(net "SW_PVDD11_S3_P1_SW2")
		)
		(pad "25_29" smd rect
			(at 1.549908 -1.279906 270)
			(size 2.0574 2.3114)
			(layers "F.Cu" "F.Mask" "F.Paste")
			(net "SW_P12V_AUX_PVDD11_S3_P1_FLT")
		)
		(pad "30" smd rect
			(at 2.05994 -2.899918)
			(size 0.2286 0.6096)
			(layers "F.Cu" "F.Mask" "F.Paste")
			(net "SW_P12V_AUX_PVDD11_S3_P1_FLT")
		)
		(pad "31" smd rect
			(at 1.610106 -2.899918)
			(size 0.2286 0.6096)
			(layers "F.Cu" "F.Mask" "F.Paste")
			(net "NC_PVDD11_S3_P1_DNC2")
		)
		(pad "32" smd rect
			(at 1.160018 -2.899918)
			(size 0.2286 0.6096)
			(layers "F.Cu" "F.Mask" "F.Paste")
			(net "SW_PVDD11_S3_P1_PH2")
		)
		(pad "33" smd rect
			(at 0.70993 -2.899918)
			(size 0.2286 0.6096)
			(layers "F.Cu" "F.Mask" "F.Paste")
			(net "SW_PVDD11_S3_P1_BOOT2")
		)
		(pad "34" smd rect
			(at 0.260096 -2.899918)
			(size 0.2286 0.6096)
			(layers "F.Cu" "F.Mask" "F.Paste")
			(net "PVDD11_S3_P1_PWM2")
		)
		(pad "35" smd rect
			(at -0.189992 -2.899918)
			(size 0.2286 0.6096)
			(layers "F.Cu" "F.Mask" "F.Paste")
			(net "PVDD11_S3_P1_VCC2")
		)
		(pad "36" smd rect
			(at -0.64008 -2.899918)
			(size 0.2286 0.6096)
			(layers "F.Cu" "F.Mask" "F.Paste")
			(net "PVDD11_S3_P1_TEMP0")
		)
		(pad "37" smd rect
			(at -1.089914 -2.899918)
			(size 0.2286 0.6096)
			(layers "F.Cu" "F.Mask" "F.Paste")
			(net "PVDD11_S3_P1_LSET2")
		)
		(pad "38" smd rect
			(at -1.540002 -2.899918)
			(size 0.2286 0.6096)
			(layers "F.Cu" "F.Mask" "F.Paste")
			(net "PVDD11_S3_P1_IMON2")
		)
		(pad "39" smd rect
			(at -1.99009 -2.899918)
			(size 0.2286 0.6096)
			(layers "F.Cu" "F.Mask" "F.Paste")
			(net "PVDD11_S3_P1_VCCS")
		)
		(pad "40" smd rect
			(at -0.87503 -1.27508)
			(size 1.7526 1.9558)
			(layers "F.Cu" "F.Mask" "F.Paste")
			(net "GND")
		)
		(pad "41" smd rect
			(at -1.525016 0.249936 270)
			(size 0.3048 0.4572)
			(layers "F.Cu" "F.Mask" "F.Paste")
			(net "NC_PVDD11_S3_P1_GL2_2")
		)
		(zone
			(layer "F.Cu")
			(hatch none 0.5)
			(connect_pads
				(clearance 0)
			)
			(min_thickness 0.25)
			(keepout
				(tracks not_allowed)
				(vias allowed)
				(pads allowed)
				(copperpour not_allowed)
				(footprints allowed)
			)
			(placement
				(enabled no)
				(sheetname "")
			)
			(fill
				(thermal_gap 0.5)
				(thermal_bridge_width 0.5)
				(island_removal_mode 0)
			)
			(polygon
				(pts
					(xy 188.746384 -348.774512) (xy 188.746384 -349.070168) (xy 193.746628 -349.070168) (xy 193.746628 -348.320868)
					(xy 193.456306 -348.320868) (xy 193.456306 -348.776544) (xy 189.036706 -348.776544) (xy 189.036706 -348.774512)
				)
			)
		)
		(zone
			(layer "F.Cu")
			(hatch none 0.5)
			(connect_pads
				(clearance 0)
			)
			(min_thickness 0.25)
			(keepout
				(tracks not_allowed)
				(vias allowed)
				(pads allowed)
				(copperpour not_allowed)
				(footprints allowed)
			)
			(placement
				(enabled no)
				(sheetname "")
			)
			(fill
				(thermal_gap 0.5)
				(thermal_bridge_width 0.5)
				(island_removal_mode 0)
			)
			(polygon
				(pts
					(xy 191.298576 -351.57664) (xy 191.298576 -353.624642) (xy 189.444376 -353.624642) (xy 189.444376 -353.383596)
					(xy 189.20206 -353.383596) (xy 189.20206 -353.86518) (xy 193.023744 -353.86518) (xy 193.023744 -353.680268)
					(xy 191.589914 -353.680268) (xy 191.589914 -351.521268) (xy 193.746628 -351.521268) (xy 193.746628 -351.271586)
					(xy 191.60363 -351.271586)
				)
			)
		)
	)
	(footprint ""
		(layer "F.Cu")
		(at 12.987782 -415.263584 90)
		(property "Reference" "PR6543"
			(at 0 0 90)
			(layer "F.SilkS")
			(hide yes)
			(effects
				(font
					(size 1.27 1.27)
				)
			)
		)
		(property "Value" ""
			(at 0 0 90)
			(layer "F.Fab")
			(effects
				(font
					(size 1.27 1.27)
				)
			)
		)
		(duplicate_pad_numbers_are_jumpers no)
		(fp_line
			(start 0.7874 -0.4064)
			(end 0.7874 0.4064)
			(stroke
				(width 0.1524)
				(type default)
			)
			(layer "F.SilkS")
		)
		(fp_line
			(start -0.7874 -0.4064)
			(end 0.7874 -0.4064)
			(stroke
				(width 0.1524)
				(type default)
			)
			(layer "F.SilkS")
		)
		(fp_line
			(start 0.7874 0.4064)
			(end -0.7874 0.4064)
			(stroke
				(width 0.1524)
				(type default)
			)
			(layer "F.SilkS")
		)
		(fp_line
			(start -0.7874 0.4064)
			(end -0.7874 -0.4064)
			(stroke
				(width 0.1524)
				(type default)
			)
			(layer "F.SilkS")
		)
		(fp_line
			(start -0.12065 -0.305054)
			(end -0.12065 -0.2794)
			(stroke
				(width 0.1)
				(type default)
			)
			(layer "F.Fab")
		)
		(fp_line
			(start -0.67945 -0.305054)
			(end -0.12065 -0.305054)
			(stroke
				(width 0.1)
				(type default)
			)
			(layer "F.Fab")
		)
		(fp_line
			(start 0.67945 -0.3048)
			(end 0.67945 0.3048)
			(stroke
				(width 0.1)
				(type default)
			)
			(layer "F.Fab")
		)
		(fp_line
			(start 0.12065 -0.3048)
			(end 0.67945 -0.3048)
			(stroke
				(width 0.1)
				(type default)
			)
			(layer "F.Fab")
		)
		(fp_line
			(start 0.12065 -0.2794)
			(end 0.12065 -0.3048)
			(stroke
				(width 0.1)
				(type default)
			)
			(layer "F.Fab")
		)
		(fp_line
			(start -0.12065 -0.2794)
			(end 0.12065 -0.2794)
			(stroke
				(width 0.1)
				(type default)
			)
			(layer "F.Fab")
		)
		(fp_line
			(start 0.120396 0.2794)
			(end -0.12065 0.2794)
			(stroke
				(width 0.1)
				(type default)
			)
			(layer "F.Fab")
		)
		(fp_line
			(start -0.12065 0.2794)
			(end -0.12065 0.3048)
			(stroke
				(width 0.1)
				(type default)
			)
			(layer "F.Fab")
		)
		(fp_line
			(start 0.67945 0.3048)
			(end 0.120396 0.3048)
			(stroke
				(width 0.1)
				(type default)
			)
			(layer "F.Fab")
		)
		(fp_line
			(start 0.120396 0.3048)
			(end 0.120396 0.2794)
			(stroke
				(width 0.1)
				(type default)
			)
			(layer "F.Fab")
		)
		(fp_line
			(start -0.12065 0.3048)
			(end -0.67945 0.3048)
			(stroke
				(width 0.1)
				(type default)
			)
			(layer "F.Fab")
		)
		(fp_line
			(start -0.67945 0.3048)
			(end -0.67945 -0.305054)
			(stroke
				(width 0.1)
				(type default)
			)
			(layer "F.Fab")
		)
		(pad "1" smd circle
			(at -0.40005 0 90)
			(size 0 0)
			(layers "F.Cu" "F.Mask" "F.Paste")
			(net "NC_P0V9_RETIMER_CPU1_IMON7")
		)
		(pad "2" smd circle
			(at 0.40005 0 90)
			(size 0 0)
			(layers "F.Cu" "F.Mask" "F.Paste")
			(net "GND")
		)
	)
)
